(kicad_pcb
	(version 20260206)
	(generator "pcbnew")
	(generator_version "10.0")
	(general
		(thickness 1.6)
		(legacy_teardrops no)
	)
	(paper "A4")
	(title_block
		(title "01162023_DA0F0TEBIF0_F0T_Expander_BD_F_brd_V02_OCP.brd")
		(comment 1 "Grand Teton / footprints 178-184 of 9728")
	)
	(layers
		(0 "F.Cu" signal "TOP")
		(4 "In1.Cu" signal "GND")
		(6 "In2.Cu" signal "VCC")
		(8 "In3.Cu" signal "VCC1")
		(10 "In4.Cu" signal "GND1")
		(12 "In5.Cu" signal "IN1")
		(14 "In6.Cu" signal "GND2")
		(16 "In7.Cu" signal "IN2")
		(18 "In8.Cu" signal "GND3")
		(20 "In9.Cu" signal "IN3")
		(22 "In10.Cu" signal "GND4")
		(24 "In11.Cu" signal "IN4")
		(26 "In12.Cu" signal "GND5")
		(28 "In13.Cu" signal "IN5")
		(30 "In14.Cu" signal "GND6")
		(32 "In15.Cu" signal "IN6")
		(34 "In16.Cu" signal "GND7")
		(2 "B.Cu" signal "BOTTOM")
		(9 "F.Adhes" user "F.Adhesive")
		(11 "B.Adhes" user "B.Adhesive")
		(13 "F.Paste" user "Package Geometry/Pastemask Top")
		(15 "B.Paste" user "Package Geometry/Pastemask Bottom")
		(5 "F.SilkS" user "Ref Des/Silkscreen Top")
		(7 "B.SilkS" user "Ref Des/Silkscreen Bottom")
		(1 "F.Mask" user "Board Geometry/Soldermask Top")
		(3 "B.Mask" user "Board Geometry/Soldermask Bottom")
		(17 "Dwgs.User" user "User.Drawings")
		(19 "Cmts.User" user "User.Comments")
		(21 "Eco1.User" user "User.Eco1")
		(23 "Eco2.User" user "User.Eco2")
		(25 "Edge.Cuts" user "Board Geometry/Outline")
		(27 "Margin" user)
		(31 "F.CrtYd" user "Package Geometry/Place Bound Top")
		(29 "B.CrtYd" user "Package Geometry/Place Bound Bottom")
		(35 "F.Fab" user "Ref Des/Assembly Top")
		(33 "B.Fab" user "Ref Des/Assembly Bottom")
	)
	(footprint ""
		(layer "F.Cu")
		(at 375.230136 -287.604708 -90)
		(property "Reference" "C3575"
			(at 0 0 270)
			(layer "F.SilkS")
			(hide yes)
			(effects
				(font
					(size 1.27 1.27)
				)
			)
		)
		(property "Value" ""
			(at 0 0 270)
			(layer "F.Fab")
			(effects
				(font
					(size 1.27 1.27)
				)
			)
		)
		(duplicate_pad_numbers_are_jumpers no)
		(fp_line
			(start -1.2954 0.5842)
			(end -1.2954 -0.5842)
			(stroke
				(width 0.1524)
				(type default)
			)
			(layer "F.SilkS")
		)
		(fp_line
			(start 1.2954 0.5842)
			(end -1.2954 0.5842)
			(stroke
				(width 0.1524)
				(type default)
			)
			(layer "F.SilkS")
		)
		(fp_line
			(start -1.2954 -0.5842)
			(end 1.2954 -0.5842)
			(stroke
				(width 0.1524)
				(type default)
			)
			(layer "F.SilkS")
		)
		(fp_line
			(start 1.2954 -0.5842)
			(end 1.2954 0.5842)
			(stroke
				(width 0.1524)
				(type default)
			)
			(layer "F.SilkS")
		)
		(fp_line
			(start -0.8636 0.4572)
			(end -0.8636 0.4064)
			(stroke
				(width 0.1)
				(type default)
			)
			(layer "F.Fab")
		)
		(fp_line
			(start 0.8636 0.4572)
			(end -0.8636 0.4572)
			(stroke
				(width 0.1)
				(type default)
			)
			(layer "F.Fab")
		)
		(fp_line
			(start -1.1938 0.4064)
			(end -1.1938 -0.4064)
			(stroke
				(width 0.1)
				(type default)
			)
			(layer "F.Fab")
		)
		(fp_line
			(start -0.8636 0.4064)
			(end -1.1938 0.4064)
			(stroke
				(width 0.1)
				(type default)
			)
			(layer "F.Fab")
		)
		(fp_line
			(start 0.8636 0.4064)
			(end 0.8636 0.4572)
			(stroke
				(width 0.1)
				(type default)
			)
			(layer "F.Fab")
		)
		(fp_line
			(start 1.1938 0.4064)
			(end 0.8636 0.4064)
			(stroke
				(width 0.1)
				(type default)
			)
			(layer "F.Fab")
		)
		(fp_line
			(start -1.1938 -0.4064)
			(end -0.8636 -0.4064)
			(stroke
				(width 0.1)
				(type default)
			)
			(layer "F.Fab")
		)
		(fp_line
			(start -0.8636 -0.4064)
			(end -0.8636 -0.4572)
			(stroke
				(width 0.1)
				(type default)
			)
			(layer "F.Fab")
		)
		(fp_line
			(start 0.8636 -0.4064)
			(end 1.1938 -0.4064)
			(stroke
				(width 0.1)
				(type default)
			)
			(layer "F.Fab")
		)
		(fp_line
			(start 1.1938 -0.4064)
			(end 1.1938 0.4064)
			(stroke
				(width 0.1)
				(type default)
			)
			(layer "F.Fab")
		)
		(fp_line
			(start -0.8636 -0.4572)
			(end 0.8636 -0.4572)
			(stroke
				(width 0.1)
				(type default)
			)
			(layer "F.Fab")
		)
		(fp_line
			(start 0.8636 -0.4572)
			(end 0.8636 -0.4064)
			(stroke
				(width 0.1)
				(type default)
			)
			(layer "F.Fab")
		)
		(pad "1" smd rect
			(at -0.7366 0 180)
			(size 0.7112 0.8128)
			(layers "F.Cu" "F.Mask" "F.Paste")
			(net "P1V8_PLL0_PEX3")
		)
		(pad "2" smd rect
			(at 0.7366 0 180)
			(size 0.7112 0.8128)
			(layers "F.Cu" "F.Mask" "F.Paste")
			(net "GND")
		)
	)
	(footprint ""
		(layer "F.Cu")
		(at 371.968014 -19.453098)
		(property "Reference" "R1723"
			(at 0 0 0)
			(layer "F.SilkS")
			(hide yes)
			(effects
				(font
					(size 1.27 1.27)
				)
			)
		)
		(property "Value" ""
			(at 0 0 0)
			(layer "F.Fab")
			(effects
				(font
					(size 1.27 1.27)
				)
			)
		)
		(duplicate_pad_numbers_are_jumpers no)
		(fp_line
			(start -0.7874 -0.4064)
			(end 0.7874 -0.4064)
			(stroke
				(width 0.1524)
				(type default)
			)
			(layer "F.SilkS")
		)
		(fp_line
			(start -0.7874 0.4064)
			(end -0.7874 -0.4064)
			(stroke
				(width 0.1524)
				(type default)
			)
			(layer "F.SilkS")
		)
		(fp_line
			(start 0.7874 -0.4064)
			(end 0.7874 0.4064)
			(stroke
				(width 0.1524)
				(type default)
			)
			(layer "F.SilkS")
		)
		(fp_line
			(start 0.7874 0.4064)
			(end -0.7874 0.4064)
			(stroke
				(width 0.1524)
				(type default)
			)
			(layer "F.SilkS")
		)
		(fp_line
			(start -0.67945 -0.305054)
			(end -0.12065 -0.305054)
			(stroke
				(width 0.1)
				(type default)
			)
			(layer "F.Fab")
		)
		(fp_line
			(start -0.67945 0.3048)
			(end -0.67945 -0.305054)
			(stroke
				(width 0.1)
				(type default)
			)
			(layer "F.Fab")
		)
		(fp_line
			(start -0.12065 -0.305054)
			(end -0.12065 -0.2794)
			(stroke
				(width 0.1)
				(type default)
			)
			(layer "F.Fab")
		)
		(fp_line
			(start -0.12065 -0.2794)
			(end 0.12065 -0.2794)
			(stroke
				(width 0.1)
				(type default)
			)
			(layer "F.Fab")
		)
		(fp_line
			(start -0.12065 0.2794)
			(end -0.12065 0.3048)
			(stroke
				(width 0.1)
				(type default)
			)
			(layer "F.Fab")
		)
		(fp_line
			(start -0.12065 0.3048)
			(end -0.67945 0.3048)
			(stroke
				(width 0.1)
				(type default)
			)
			(layer "F.Fab")
		)
		(fp_line
			(start 0.120396 0.2794)
			(end -0.12065 0.2794)
			(stroke
				(width 0.1)
				(type default)
			)
			(layer "F.Fab")
		)
		(fp_line
			(start 0.120396 0.3048)
			(end 0.120396 0.2794)
			(stroke
				(width 0.1)
				(type default)
			)
			(layer "F.Fab")
		)
		(fp_line
			(start 0.12065 -0.3048)
			(end 0.67945 -0.3048)
			(stroke
				(width 0.1)
				(type default)
			)
			(layer "F.Fab")
		)
		(fp_line
			(start 0.12065 -0.2794)
			(end 0.12065 -0.3048)
			(stroke
				(width 0.1)
				(type default)
			)
			(layer "F.Fab")
		)
		(fp_line
			(start 0.67945 -0.3048)
			(end 0.67945 0.3048)
			(stroke
				(width 0.1)
				(type default)
			)
			(layer "F.Fab")
		)
		(fp_line
			(start 0.67945 0.3048)
			(end 0.120396 0.3048)
			(stroke
				(width 0.1)
				(type default)
			)
			(layer "F.Fab")
		)
		(pad "1" smd circle
			(at -0.40005 0)
			(size 0 0)
			(layers "F.Cu" "F.Mask" "F.Paste")
			(net "SMB_ISO_SSD12_R_SDA")
		)
		(pad "2" smd circle
			(at 0.40005 0)
			(size 0 0)
			(layers "F.Cu" "F.Mask" "F.Paste")
			(net "SMB_ISO_SSD12_SDA")
		)
	)
	(footprint ""
		(layer "F.Cu")
		(at 255.020572 -70.307454 90)
		(property "Reference" "PC859"
			(at 0 0 90)
			(layer "F.SilkS")
			(hide yes)
			(effects
				(font
					(size 1.27 1.27)
				)
			)
		)
		(property "Value" ""
			(at 0 0 90)
			(layer "F.Fab")
			(effects
				(font
					(size 1.27 1.27)
				)
			)
		)
		(duplicate_pad_numbers_are_jumpers no)
		(fp_line
			(start 0.7874 -0.4064)
			(end 0.7874 0.4064)
			(stroke
				(width 0.1524)
				(type default)
			)
			(layer "F.SilkS")
		)
		(fp_line
			(start -0.7874 -0.4064)
			(end 0.7874 -0.4064)
			(stroke
				(width 0.1524)
				(type default)
			)
			(layer "F.SilkS")
		)
		(fp_line
			(start 0.7874 0.4064)
			(end -0.7874 0.4064)
			(stroke
				(width 0.1524)
				(type default)
			)
			(layer "F.SilkS")
		)
		(fp_line
			(start -0.7874 0.4064)
			(end -0.7874 -0.4064)
			(stroke
				(width 0.1524)
				(type default)
			)
			(layer "F.SilkS")
		)
		(fp_line
			(start -0.12065 -0.305054)
			(end -0.12065 -0.2794)
			(stroke
				(width 0.1)
				(type default)
			)
			(layer "F.Fab")
		)
		(fp_line
			(start -0.67945 -0.305054)
			(end -0.12065 -0.305054)
			(stroke
				(width 0.1)
				(type default)
			)
			(layer "F.Fab")
		)
		(fp_line
			(start 0.67945 -0.3048)
			(end 0.67945 0.3048)
			(stroke
				(width 0.1)
				(type default)
			)
			(layer "F.Fab")
		)
		(fp_line
			(start 0.12065 -0.3048)
			(end 0.67945 -0.3048)
			(stroke
				(width 0.1)
				(type default)
			)
			(layer "F.Fab")
		)
		(fp_line
			(start 0.12065 -0.2794)
			(end 0.12065 -0.3048)
			(stroke
				(width 0.1)
				(type default)
			)
			(layer "F.Fab")
		)
		(fp_line
			(start -0.12065 -0.2794)
			(end 0.12065 -0.2794)
			(stroke
				(width 0.1)
				(type default)
			)
			(layer "F.Fab")
		)
		(fp_line
			(start 0.120396 0.2794)
			(end -0.12065 0.2794)
			(stroke
				(width 0.1)
				(type default)
			)
			(layer "F.Fab")
		)
		(fp_line
			(start -0.12065 0.2794)
			(end -0.12065 0.3048)
			(stroke
				(width 0.1)
				(type default)
			)
			(layer "F.Fab")
		)
		(fp_line
			(start 0.67945 0.3048)
			(end 0.120396 0.3048)
			(stroke
				(width 0.1)
				(type default)
			)
			(layer "F.Fab")
		)
		(fp_line
			(start 0.120396 0.3048)
			(end 0.120396 0.2794)
			(stroke
				(width 0.1)
				(type default)
			)
			(layer "F.Fab")
		)
		(fp_line
			(start -0.12065 0.3048)
			(end -0.67945 0.3048)
			(stroke
				(width 0.1)
				(type default)
			)
			(layer "F.Fab")
		)
		(fp_line
			(start -0.67945 0.3048)
			(end -0.67945 -0.305054)
			(stroke
				(width 0.1)
				(type default)
			)
			(layer "F.Fab")
		)
		(pad "1" smd circle
			(at -0.40005 0 90)
			(size 0 0)
			(layers "F.Cu" "F.Mask" "F.Paste")
			(net "P12V_AUX")
		)
		(pad "2" smd circle
			(at 0.40005 0 90)
			(size 0 0)
			(layers "F.Cu" "F.Mask" "F.Paste")
			(net "GND")
		)
	)
	(footprint ""
		(layer "F.Cu")
		(at 338.074 -157.734 180)
		(property "Reference" "R4814"
			(at 0 0 180)
			(layer "F.SilkS")
			(hide yes)
			(effects
				(font
					(size 1.27 1.27)
				)
			)
		)
		(property "Value" ""
			(at 0 0 180)
			(layer "F.Fab")
			(effects
				(font
					(size 1.27 1.27)
				)
			)
		)
		(duplicate_pad_numbers_are_jumpers no)
		(fp_line
			(start 0.7874 0.4064)
			(end -0.7874 0.4064)
			(stroke
				(width 0.1524)
				(type default)
			)
			(layer "F.SilkS")
		)
		(fp_line
			(start 0.7874 -0.4064)
			(end 0.7874 0.4064)
			(stroke
				(width 0.1524)
				(type default)
			)
			(layer "F.SilkS")
		)
		(fp_line
			(start -0.7874 0.4064)
			(end -0.7874 -0.4064)
			(stroke
				(width 0.1524)
				(type default)
			)
			(layer "F.SilkS")
		)
		(fp_line
			(start -0.7874 -0.4064)
			(end 0.7874 -0.4064)
			(stroke
				(width 0.1524)
				(type default)
			)
			(layer "F.SilkS")
		)
		(fp_line
			(start 0.67945 0.3048)
			(end 0.120396 0.3048)
			(stroke
				(width 0.1)
				(type default)
			)
			(layer "F.Fab")
		)
		(fp_line
			(start 0.67945 -0.3048)
			(end 0.67945 0.3048)
			(stroke
				(width 0.1)
				(type default)
			)
			(layer "F.Fab")
		)
		(fp_line
			(start 0.12065 -0.2794)
			(end 0.12065 -0.3048)
			(stroke
				(width 0.1)
				(type default)
			)
			(layer "F.Fab")
		)
		(fp_line
			(start 0.12065 -0.3048)
			(end 0.67945 -0.3048)
			(stroke
				(width 0.1)
				(type default)
			)
			(layer "F.Fab")
		)
		(fp_line
			(start 0.120396 0.3048)
			(end 0.120396 0.2794)
			(stroke
				(width 0.1)
				(type default)
			)
			(layer "F.Fab")
		)
		(fp_line
			(start 0.120396 0.2794)
			(end -0.12065 0.2794)
			(stroke
				(width 0.1)
				(type default)
			)
			(layer "F.Fab")
		)
		(fp_line
			(start -0.12065 0.3048)
			(end -0.67945 0.3048)
			(stroke
				(width 0.1)
				(type default)
			)
			(layer "F.Fab")
		)
		(fp_line
			(start -0.12065 0.2794)
			(end -0.12065 0.3048)
			(stroke
				(width 0.1)
				(type default)
			)
			(layer "F.Fab")
		)
		(fp_line
			(start -0.12065 -0.2794)
			(end 0.12065 -0.2794)
			(stroke
				(width 0.1)
				(type default)
			)
			(layer "F.Fab")
		)
		(fp_line
			(start -0.12065 -0.305054)
			(end -0.12065 -0.2794)
			(stroke
				(width 0.1)
				(type default)
			)
			(layer "F.Fab")
		)
		(fp_line
			(start -0.67945 0.3048)
			(end -0.67945 -0.305054)
			(stroke
				(width 0.1)
				(type default)
			)
			(layer "F.Fab")
		)
		(fp_line
			(start -0.67945 -0.305054)
			(end -0.12065 -0.305054)
			(stroke
				(width 0.1)
				(type default)
			)
			(layer "F.Fab")
		)
		(pad "1" smd circle
			(at -0.40005 0 180)
			(size 0 0)
			(layers "F.Cu" "F.Mask" "F.Paste")
			(net "RST_PEX_SSD12_PERST_N")
		)
		(pad "2" smd circle
			(at 0.40005 0 180)
			(size 0 0)
			(layers "F.Cu" "F.Mask" "F.Paste")
			(net "RST_PEX_SSD12_PERST_R_N")
		)
	)
	(footprint ""
		(layer "F.Cu")
		(at 353.695 -171.45)
		(property "Reference" "R4782"
			(at 0 0 0)
			(layer "F.SilkS")
			(hide yes)
			(effects
				(font
					(size 1.27 1.27)
				)
			)
		)
		(property "Value" ""
			(at 0 0 0)
			(layer "F.Fab")
			(effects
				(font
					(size 1.27 1.27)
				)
			)
		)
		(duplicate_pad_numbers_are_jumpers no)
		(fp_line
			(start -0.7874 -0.4064)
			(end 0.7874 -0.4064)
			(stroke
				(width 0.1524)
				(type default)
			)
			(layer "F.SilkS")
		)
		(fp_line
			(start -0.7874 0.4064)
			(end -0.7874 -0.4064)
			(stroke
				(width 0.1524)
				(type default)
			)
			(layer "F.SilkS")
		)
		(fp_line
			(start 0.7874 -0.4064)
			(end 0.7874 0.4064)
			(stroke
				(width 0.1524)
				(type default)
			)
			(layer "F.SilkS")
		)
		(fp_line
			(start 0.7874 0.4064)
			(end -0.7874 0.4064)
			(stroke
				(width 0.1524)
				(type default)
			)
			(layer "F.SilkS")
		)
		(fp_line
			(start -0.67945 -0.305054)
			(end -0.12065 -0.305054)
			(stroke
				(width 0.1)
				(type default)
			)
			(layer "F.Fab")
		)
		(fp_line
			(start -0.67945 0.3048)
			(end -0.67945 -0.305054)
			(stroke
				(width 0.1)
				(type default)
			)
			(layer "F.Fab")
		)
		(fp_line
			(start -0.12065 -0.305054)
			(end -0.12065 -0.2794)
			(stroke
				(width 0.1)
				(type default)
			)
			(layer "F.Fab")
		)
		(fp_line
			(start -0.12065 -0.2794)
			(end 0.12065 -0.2794)
			(stroke
				(width 0.1)
				(type default)
			)
			(layer "F.Fab")
		)
		(fp_line
			(start -0.12065 0.2794)
			(end -0.12065 0.3048)
			(stroke
				(width 0.1)
				(type default)
			)
			(layer "F.Fab")
		)
		(fp_line
			(start -0.12065 0.3048)
			(end -0.67945 0.3048)
			(stroke
				(width 0.1)
				(type default)
			)
			(layer "F.Fab")
		)
		(fp_line
			(start 0.120396 0.2794)
			(end -0.12065 0.2794)
			(stroke
				(width 0.1)
				(type default)
			)
			(layer "F.Fab")
		)
		(fp_line
			(start 0.120396 0.3048)
			(end 0.120396 0.2794)
			(stroke
				(width 0.1)
				(type default)
			)
			(layer "F.Fab")
		)
		(fp_line
			(start 0.12065 -0.3048)
			(end 0.67945 -0.3048)
			(stroke
				(width 0.1)
				(type default)
			)
			(layer "F.Fab")
		)
		(fp_line
			(start 0.12065 -0.2794)
			(end 0.12065 -0.3048)
			(stroke
				(width 0.1)
				(type default)
			)
			(layer "F.Fab")
		)
		(fp_line
			(start 0.67945 -0.3048)
			(end 0.67945 0.3048)
			(stroke
				(width 0.1)
				(type default)
			)
			(layer "F.Fab")
		)
		(fp_line
			(start 0.67945 0.3048)
			(end 0.120396 0.3048)
			(stroke
				(width 0.1)
				(type default)
			)
			(layer "F.Fab")
		)
		(pad "1" smd circle
			(at -0.40005 0)
			(size 0 0)
			(layers "F.Cu" "F.Mask" "F.Paste")
			(net "GND")
		)
		(pad "2" smd circle
			(at 0.40005 0)
			(size 0 0)
			(layers "F.Cu" "F.Mask" "F.Paste")
			(net "PCA9555_1_PEX2_A0")
		)
	)
	(footprint ""
		(layer "F.Cu")
		(at 44.178728 -356.244906 90)
		(property "Reference" "C2176"
			(at 0 0 90)
			(layer "F.SilkS")
			(hide yes)
			(effects
				(font
					(size 1.27 1.27)
				)
			)
		)
		(property "Value" ""
			(at 0 0 90)
			(layer "F.Fab")
			(effects
				(font
					(size 1.27 1.27)
				)
			)
		)
		(duplicate_pad_numbers_are_jumpers no)
		(fp_line
			(start 0.299974 -0.150114)
			(end 0.299974 0.150114)
			(stroke
				(width 0.1)
				(type default)
			)
			(layer "F.Fab")
		)
		(fp_line
			(start -0.299974 -0.150114)
			(end 0.299974 -0.150114)
			(stroke
				(width 0.1)
				(type default)
			)
			(layer "F.Fab")
		)
		(fp_line
			(start 0.299974 0.150114)
			(end -0.299974 0.150114)
			(stroke
				(width 0.1)
				(type default)
			)
			(layer "F.Fab")
		)
		(fp_line
			(start -0.299974 0.150114)
			(end -0.299974 -0.150114)
			(stroke
				(width 0.1)
				(type default)
			)
			(layer "F.Fab")
		)
		(pad "1" smd rect
			(at -0.2667 0 90)
			(size 0.3048 0.381)
			(layers "F.Cu" "F.Mask" "F.Paste")
			(net "P5E_PEX0_STN4_TX_DP<67>")
		)
		(pad "2" smd rect
			(at 0.2667 0 90)
			(size 0.3048 0.381)
			(layers "F.Cu" "F.Mask" "F.Paste")
			(net "P5E_PEX0_STN4_TX_C_DP<67>")
		)
	)
	(footprint ""
		(layer "F.Cu")
		(at 133.177026 -193.136774 -90)
		(property "Reference" "R6667"
			(at 0 0 270)
			(layer "F.SilkS")
			(hide yes)
			(effects
				(font
					(size 1.27 1.27)
				)
			)
		)
		(property "Value" ""
			(at 0 0 270)
			(layer "F.Fab")
			(effects
				(font
					(size 1.27 1.27)
				)
			)
		)
		(duplicate_pad_numbers_are_jumpers no)
		(fp_line
			(start -0.7874 0.4064)
			(end -0.7874 -0.4064)
			(stroke
				(width 0.1524)
				(type default)
			)
			(layer "F.SilkS")
		)
		(fp_line
			(start 0.7874 0.4064)
			(end -0.7874 0.4064)
			(stroke
				(width 0.1524)
				(type default)
			)
			(layer "F.SilkS")
		)
		(fp_line
			(start -0.7874 -0.4064)
			(end 0.7874 -0.4064)
			(stroke
				(width 0.1524)
				(type default)
			)
			(layer "F.SilkS")
		)
		(fp_line
			(start 0.7874 -0.4064)
			(end 0.7874 0.4064)
			(stroke
				(width 0.1524)
				(type default)
			)
			(layer "F.SilkS")
		)
		(fp_line
			(start -0.67945 0.3048)
			(end -0.67945 -0.305054)
			(stroke
				(width 0.1)
				(type default)
			)
			(layer "F.Fab")
		)
		(fp_line
			(start -0.12065 0.3048)
			(end -0.67945 0.3048)
			(stroke
				(width 0.1)
				(type default)
			)
			(layer "F.Fab")
		)
		(fp_line
			(start 0.120396 0.3048)
			(end 0.120396 0.2794)
			(stroke
				(width 0.1)
				(type default)
			)
			(layer "F.Fab")
		)
		(fp_line
			(start 0.67945 0.3048)
			(end 0.120396 0.3048)
			(stroke
				(width 0.1)
				(type default)
			)
			(layer "F.Fab")
		)
		(fp_line
			(start -0.12065 0.2794)
			(end -0.12065 0.3048)
			(stroke
				(width 0.1)
				(type default)
			)
			(layer "F.Fab")
		)
		(fp_line
			(start 0.120396 0.2794)
			(end -0.12065 0.2794)
			(stroke
				(width 0.1)
				(type default)
			)
			(layer "F.Fab")
		)
		(fp_line
			(start -0.12065 -0.2794)
			(end 0.12065 -0.2794)
			(stroke
				(width 0.1)
				(type default)
			)
			(layer "F.Fab")
		)
		(fp_line
			(start 0.12065 -0.2794)
			(end 0.12065 -0.3048)
			(stroke
				(width 0.1)
				(type default)
			)
			(layer "F.Fab")
		)
		(fp_line
			(start 0.12065 -0.3048)
			(end 0.67945 -0.3048)
			(stroke
				(width 0.1)
				(type default)
			)
			(layer "F.Fab")
		)
		(fp_line
			(start 0.67945 -0.3048)
			(end 0.67945 0.3048)
			(stroke
				(width 0.1)
				(type default)
			)
			(layer "F.Fab")
		)
		(fp_line
			(start -0.67945 -0.305054)
			(end -0.12065 -0.305054)
			(stroke
				(width 0.1)
				(type default)
			)
			(layer "F.Fab")
		)
		(fp_line
			(start -0.12065 -0.305054)
			(end -0.12065 -0.2794)
			(stroke
				(width 0.1)
				(type default)
			)
			(layer "F.Fab")
		)
		(pad "1" smd circle
			(at -0.40005 0 270)
			(size 0 0)
			(layers "F.Cu" "F.Mask" "F.Paste")
			(net "NIC6_CLK_EN_BUF_N")
		)
		(pad "2" smd circle
			(at 0.40005 0 270)
			(size 0 0)
			(layers "F.Cu" "F.Mask" "F.Paste")
			(net "NIC6_CLK_EN_BUF_R_N")
		)
	)
)
